G04 ================== begin FILE IDENTIFICATION RECORD ==================*
G04 Layout Name:  15105-sa.brd*
G04 Film Name:    GOLD_T*
G04 File Format:  Gerber RS274X*
G04 File Origin:  Cadence Allegro 16.5-S056*
G04 Origin Date:  Wed Nov 16 02:02:06 2016*
G04 *
G04 Layer:  PACKAGE GEOMETRY/GOLDEN_TOP*
G04 Layer:  DRAWING FORMAT/LAYER_GOLD_T*
G04 Layer:  DRAWING FORMAT/LAYER_PCB_STORY*
G04 Layer:  BOARD GEOMETRY/GOLDEN_TOP*
G04 Layer:  BOARD GEOMETRY/PANEL_OUTLINE*
G04 *
G04 Offset:    (0.00 0.00)*
G04 Mirror:    No*
G04 Mode:      Positive*
G04 Rotation:  0*
G04 FullContactRelief:  No*
G04 UndefLineWidth:     6.00*
G04 ================== end FILE IDENTIFICATION RECORD ====================*
%FSLAX35Y35*MOIN*%
%IR0*IPPOS*OFA0.00000B0.00000*MIA0B0*SFA1.00000B1.00000*%
%ADD10C,.02*%
%ADD11C,.006*%
G75*
%LPD*%
G75*
G36*
G01X116455Y890820D02*
X114255D01*
Y883420D01*
X116455D01*
Y890820D01*
G37*
G36*
G01X119604Y892520D02*
X117404D01*
Y883420D01*
X119604D01*
Y892520D01*
G37*
G36*
G01X122754D02*
X120554D01*
Y883420D01*
X122754D01*
Y892520D01*
G37*
G36*
G01X125903D02*
X123703D01*
Y883420D01*
X125903D01*
Y892520D01*
G37*
G36*
G01X129053D02*
X126853D01*
Y883420D01*
X129053D01*
Y892520D01*
G37*
G36*
G01X132203D02*
X130003D01*
Y883420D01*
X132203D01*
Y892520D01*
G37*
G36*
G01X135352D02*
X133152D01*
Y883420D01*
X135352D01*
Y892520D01*
G37*
G36*
G01X138502D02*
X136302D01*
Y883420D01*
X138502D01*
Y892520D01*
G37*
G36*
G01X141651D02*
X139451D01*
Y883420D01*
X141651D01*
Y892520D01*
G37*
G36*
G01X144801D02*
X142601D01*
Y883420D01*
X144801D01*
Y892520D01*
G37*
G36*
G01X147951D02*
X145751D01*
Y883420D01*
X147951D01*
Y892520D01*
G37*
G36*
G01X151100D02*
X148900D01*
Y883420D01*
X151100D01*
Y892520D01*
G37*
G36*
G01X154250D02*
X152050D01*
Y883420D01*
X154250D01*
Y892520D01*
G37*
G36*
G01X157400D02*
X155200D01*
Y883420D01*
X157400D01*
Y892520D01*
G37*
G36*
G01X160549D02*
X158349D01*
Y883420D01*
X160549D01*
Y892520D01*
G37*
G36*
G01X163699D02*
X161499D01*
Y883420D01*
X163699D01*
Y892520D01*
G37*
G36*
G01X166848D02*
X164648D01*
Y883420D01*
X166848D01*
Y892520D01*
G37*
G36*
G01X192045D02*
X189845D01*
Y883420D01*
X192045D01*
Y892520D01*
G37*
G36*
G01X169998D02*
X167798D01*
Y883420D01*
X169998D01*
Y892520D01*
G37*
G36*
G01X173148D02*
X170948D01*
Y883420D01*
X173148D01*
Y892520D01*
G37*
G36*
G01X176297D02*
X174097D01*
Y883420D01*
X176297D01*
Y892520D01*
G37*
G36*
G01X179447D02*
X177247D01*
Y883420D01*
X179447D01*
Y892520D01*
G37*
G36*
G01X182596D02*
X180396D01*
Y883420D01*
X182596D01*
Y892520D01*
G37*
G36*
G01X185746D02*
X183546D01*
Y883420D01*
X185746D01*
Y892520D01*
G37*
G36*
G01X188896D02*
X186696D01*
Y883420D01*
X188896D01*
Y892520D01*
G37*
G36*
G01X195195D02*
X192995D01*
Y883420D01*
X195195D01*
Y892520D01*
G37*
G36*
G01X198344D02*
X196144D01*
Y883420D01*
X198344D01*
Y892520D01*
G37*
G36*
G01X201494D02*
X199294D01*
Y883420D01*
X201494D01*
Y892520D01*
G37*
G36*
G01X204644D02*
X202444D01*
Y883420D01*
X204644D01*
Y892520D01*
G37*
G36*
G01X207793D02*
X205593D01*
Y883420D01*
X207793D01*
Y892520D01*
G37*
G36*
G01X210943D02*
X208743D01*
Y883420D01*
X210943D01*
Y892520D01*
G37*
G36*
G01X214092D02*
X211892D01*
Y883420D01*
X214092D01*
Y892520D01*
G37*
G36*
G01X217242D02*
X215042D01*
Y883420D01*
X217242D01*
Y892520D01*
G37*
G36*
G01X220392D02*
X218192D01*
Y883420D01*
X220392D01*
Y892520D01*
G37*
G36*
G01X223541D02*
X221341D01*
Y883420D01*
X223541D01*
Y892520D01*
G37*
G36*
G01X226691D02*
X224491D01*
Y883420D01*
X226691D01*
Y892520D01*
G37*
G36*
G01X229840D02*
X227640D01*
Y883420D01*
X229840D01*
Y892520D01*
G37*
G36*
G01X232990D02*
X230790D01*
Y883420D01*
X232990D01*
Y892520D01*
G37*
G36*
G01X236140D02*
X233940D01*
Y883420D01*
X236140D01*
Y892520D01*
G37*
G36*
G01X239289D02*
X237089D01*
Y883420D01*
X239289D01*
Y892520D01*
G37*
G36*
G01X242439D02*
X240239D01*
Y883420D01*
X242439D01*
Y892520D01*
G37*
G36*
G01X245588D02*
X243388D01*
Y883420D01*
X245588D01*
Y892520D01*
G37*
G36*
G01X248738D02*
X246538D01*
Y883420D01*
X248738D01*
Y892520D01*
G37*
G36*
G01X251888D02*
X249688D01*
Y883420D01*
X251888D01*
Y892520D01*
G37*
G36*
G01X261337D02*
X259137D01*
Y883420D01*
X261337D01*
Y892520D01*
G37*
G36*
G01X264486D02*
X262286D01*
Y883420D01*
X264486D01*
Y892520D01*
G37*
G36*
G01X267636D02*
X265436D01*
Y883420D01*
X267636D01*
Y892520D01*
G37*
G36*
G01X255037D02*
X252837D01*
Y883420D01*
X255037D01*
Y892520D01*
G37*
G36*
G01X258187D02*
X255987D01*
Y883420D01*
X258187D01*
Y892520D01*
G37*
G36*
G01X270785D02*
X268585D01*
Y883420D01*
X270785D01*
Y892520D01*
G37*
G36*
G01X273935D02*
X271735D01*
Y883420D01*
X273935D01*
Y892520D01*
G37*
G36*
G01X277085D02*
X274885D01*
Y883420D01*
X277085D01*
Y892520D01*
G37*
G36*
G01X280234D02*
X278034D01*
Y883420D01*
X280234D01*
Y892520D01*
G37*
G36*
G01X286533Y890820D02*
X284333D01*
Y883420D01*
X286533D01*
Y890820D01*
G37*
G36*
G01X283384Y892520D02*
X281184D01*
Y883420D01*
X283384D01*
Y892520D01*
G37*
G36*
G01X289683D02*
X287483D01*
Y883420D01*
X289683D01*
Y892520D01*
G37*
G36*
G01X305431D02*
X303231D01*
Y883420D01*
X305431D01*
Y892520D01*
G37*
G36*
G01X308581D02*
X306381D01*
Y883420D01*
X308581D01*
Y892520D01*
G37*
G36*
G01X311730D02*
X309530D01*
Y883420D01*
X311730D01*
Y892520D01*
G37*
G36*
G01X314880D02*
X312680D01*
Y883420D01*
X314880D01*
Y892520D01*
G37*
G36*
G01X318029D02*
X315829D01*
Y883420D01*
X318029D01*
Y892520D01*
G37*
G36*
G01X321179D02*
X318979D01*
Y883420D01*
X321179D01*
Y892520D01*
G37*
G36*
G01X324329D02*
X322129D01*
Y883420D01*
X324329D01*
Y892520D01*
G37*
G36*
G01X327478D02*
X325278D01*
Y883420D01*
X327478D01*
Y892520D01*
G37*
G36*
G01X330628D02*
X328428D01*
Y883420D01*
X330628D01*
Y892520D01*
G37*
G36*
G01X333777D02*
X331577D01*
Y883420D01*
X333777D01*
Y892520D01*
G37*
G36*
G01X336927D02*
X334727D01*
Y883420D01*
X336927D01*
Y892520D01*
G37*
G36*
G01X340077D02*
X337877D01*
Y883420D01*
X340077D01*
Y892520D01*
G37*
G36*
G01X343226D02*
X341026D01*
Y883420D01*
X343226D01*
Y892520D01*
G37*
G36*
G01X346376D02*
X344176D01*
Y883420D01*
X346376D01*
Y892520D01*
G37*
G36*
G01X349526D02*
X347326D01*
Y883420D01*
X349526D01*
Y892520D01*
G37*
G36*
G01X352675D02*
X350475D01*
Y883420D01*
X352675D01*
Y892520D01*
G37*
G36*
G01X355825D02*
X353625D01*
Y883420D01*
X355825D01*
Y892520D01*
G37*
G36*
G01X358974D02*
X356774D01*
Y883420D01*
X358974D01*
Y892520D01*
G37*
G36*
G01X362124D02*
X359924D01*
Y883420D01*
X362124D01*
Y892520D01*
G37*
G36*
G01X365274D02*
X363074D01*
Y883420D01*
X365274D01*
Y892520D01*
G37*
G36*
G01X368423D02*
X366223D01*
Y883420D01*
X368423D01*
Y892520D01*
G37*
G36*
G01X371573D02*
X369373D01*
Y883420D01*
X371573D01*
Y892520D01*
G37*
G36*
G01X374722D02*
X372522D01*
Y883420D01*
X374722D01*
Y892520D01*
G37*
G36*
G01X377872D02*
X375672D01*
Y883420D01*
X377872D01*
Y892520D01*
G37*
G36*
G01X381022D02*
X378822D01*
Y883420D01*
X381022D01*
Y892520D01*
G37*
G36*
G01X384171D02*
X381971D01*
Y883420D01*
X384171D01*
Y892520D01*
G37*
G36*
G01X387321D02*
X385121D01*
Y883420D01*
X387321D01*
Y892520D01*
G37*
G36*
G01X390470D02*
X388270D01*
Y883420D01*
X390470D01*
Y892520D01*
G37*
G36*
G01X393620D02*
X391420D01*
Y883420D01*
X393620D01*
Y892520D01*
G37*
G36*
G01X396770D02*
X394570D01*
Y883420D01*
X396770D01*
Y892520D01*
G37*
G36*
G01X399919D02*
X397719D01*
Y883420D01*
X399919D01*
Y892520D01*
G37*
G36*
G01X403069D02*
X400869D01*
Y883420D01*
X403069D01*
Y892520D01*
G37*
G36*
G01X406218D02*
X404018D01*
Y883420D01*
X406218D01*
Y892520D01*
G37*
G36*
G01X409368D02*
X407168D01*
Y883420D01*
X409368D01*
Y892520D01*
G37*
G36*
G01X412518D02*
X410318D01*
Y883420D01*
X412518D01*
Y892520D01*
G37*
G36*
G01X415667D02*
X413467D01*
Y883420D01*
X415667D01*
Y892520D01*
G37*
G36*
G01X418817D02*
X416617D01*
Y883420D01*
X418817D01*
Y892520D01*
G37*
G36*
G01X421966D02*
X419766D01*
Y883420D01*
X421966D01*
Y892520D01*
G37*
G36*
G01X425116D02*
X422916D01*
Y883420D01*
X425116D01*
Y892520D01*
G37*
G36*
G01X428266D02*
X426066D01*
Y883420D01*
X428266D01*
Y892520D01*
G37*
G36*
G01X431415D02*
X429215D01*
Y883420D01*
X431415D01*
Y892520D01*
G37*
G36*
G01X434565D02*
X432365D01*
Y883420D01*
X434565D01*
Y892520D01*
G37*
G36*
G01X437714D02*
X435514D01*
Y883420D01*
X437714D01*
Y892520D01*
G37*
G36*
G01X440864D02*
X438664D01*
Y883420D01*
X440864D01*
Y892520D01*
G37*
G36*
G01X533778Y890820D02*
X531578D01*
Y883420D01*
X533778D01*
Y890820D01*
G37*
G36*
G01X536927Y892520D02*
X534727D01*
Y883420D01*
X536927D01*
Y892520D01*
G37*
G36*
G01X540077D02*
X537877D01*
Y883420D01*
X540077D01*
Y892520D01*
G37*
G36*
G01X543226D02*
X541026D01*
Y883420D01*
X543226D01*
Y892520D01*
G37*
G36*
G01X546376D02*
X544176D01*
Y883420D01*
X546376D01*
Y892520D01*
G37*
G36*
G01X549526D02*
X547326D01*
Y883420D01*
X549526D01*
Y892520D01*
G37*
G36*
G01X552675D02*
X550475D01*
Y883420D01*
X552675D01*
Y892520D01*
G37*
G36*
G01X555825D02*
X553625D01*
Y883420D01*
X555825D01*
Y892520D01*
G37*
G36*
G01X558974D02*
X556774D01*
Y883420D01*
X558974D01*
Y892520D01*
G37*
G36*
G01X562124D02*
X559924D01*
Y883420D01*
X562124D01*
Y892520D01*
G37*
G36*
G01X565274D02*
X563074D01*
Y883420D01*
X565274D01*
Y892520D01*
G37*
G36*
G01X568423D02*
X566223D01*
Y883420D01*
X568423D01*
Y892520D01*
G37*
G36*
G01X571573D02*
X569373D01*
Y883420D01*
X571573D01*
Y892520D01*
G37*
G36*
G01X574723D02*
X572523D01*
Y883420D01*
X574723D01*
Y892520D01*
G37*
G36*
G01X577872D02*
X575672D01*
Y883420D01*
X577872D01*
Y892520D01*
G37*
G36*
G01X581022D02*
X578822D01*
Y883420D01*
X581022D01*
Y892520D01*
G37*
G36*
G01X584171D02*
X581971D01*
Y883420D01*
X584171D01*
Y892520D01*
G37*
G36*
G01X587321D02*
X585121D01*
Y883420D01*
X587321D01*
Y892520D01*
G37*
G36*
G01X590471D02*
X588271D01*
Y883420D01*
X590471D01*
Y892520D01*
G37*
G36*
G01X593620D02*
X591420D01*
Y883420D01*
X593620D01*
Y892520D01*
G37*
G36*
G01X596770D02*
X594570D01*
Y883420D01*
X596770D01*
Y892520D01*
G37*
G36*
G01X599919D02*
X597719D01*
Y883420D01*
X599919D01*
Y892520D01*
G37*
G36*
G01X603069D02*
X600869D01*
Y883420D01*
X603069D01*
Y892520D01*
G37*
G36*
G01X609368D02*
X607168D01*
Y883420D01*
X609368D01*
Y892520D01*
G37*
G36*
G01X606219D02*
X604019D01*
Y883420D01*
X606219D01*
Y892520D01*
G37*
G36*
G01X612518D02*
X610318D01*
Y883420D01*
X612518D01*
Y892520D01*
G37*
G36*
G01X615667D02*
X613467D01*
Y883420D01*
X615667D01*
Y892520D01*
G37*
G36*
G01X618817D02*
X616617D01*
Y883420D01*
X618817D01*
Y892520D01*
G37*
G36*
G01X621967D02*
X619767D01*
Y883420D01*
X621967D01*
Y892520D01*
G37*
G36*
G01X625116D02*
X622916D01*
Y883420D01*
X625116D01*
Y892520D01*
G37*
G36*
G01X628266D02*
X626066D01*
Y883420D01*
X628266D01*
Y892520D01*
G37*
G36*
G01X631415D02*
X629215D01*
Y883420D01*
X631415D01*
Y892520D01*
G37*
G36*
G01X634565D02*
X632365D01*
Y883420D01*
X634565D01*
Y892520D01*
G37*
G36*
G01X637715D02*
X635515D01*
Y883420D01*
X637715D01*
Y892520D01*
G37*
G36*
G01X640864D02*
X638664D01*
Y883420D01*
X640864D01*
Y892520D01*
G37*
G36*
G01X644014D02*
X641814D01*
Y883420D01*
X644014D01*
Y892520D01*
G37*
G36*
G01X647163D02*
X644963D01*
Y883420D01*
X647163D01*
Y892520D01*
G37*
G36*
G01X650313D02*
X648113D01*
Y883420D01*
X650313D01*
Y892520D01*
G37*
G36*
G01X653463D02*
X651263D01*
Y883420D01*
X653463D01*
Y892520D01*
G37*
G36*
G01X656612D02*
X654412D01*
Y883420D01*
X656612D01*
Y892520D01*
G37*
G36*
G01X659762D02*
X657562D01*
Y883420D01*
X659762D01*
Y892520D01*
G37*
G36*
G01X662911D02*
X660711D01*
Y883420D01*
X662911D01*
Y892520D01*
G37*
G36*
G01X666061D02*
X663861D01*
Y883420D01*
X666061D01*
Y892520D01*
G37*
G36*
G01X669211D02*
X667011D01*
Y883420D01*
X669211D01*
Y892520D01*
G37*
G36*
G01X672360D02*
X670160D01*
Y883420D01*
X672360D01*
Y892520D01*
G37*
G36*
G01X678660D02*
X676460D01*
Y883420D01*
X678660D01*
Y892520D01*
G37*
G36*
G01X681809D02*
X679609D01*
Y883420D01*
X681809D01*
Y892520D01*
G37*
G36*
G01X684959D02*
X682759D01*
Y883420D01*
X684959D01*
Y892520D01*
G37*
G36*
G01X688108D02*
X685908D01*
Y883420D01*
X688108D01*
Y892520D01*
G37*
G36*
G01X691258D02*
X689058D01*
Y883420D01*
X691258D01*
Y892520D01*
G37*
G36*
G01X694408D02*
X692208D01*
Y883420D01*
X694408D01*
Y892520D01*
G37*
G36*
G01X697557D02*
X695357D01*
Y883420D01*
X697557D01*
Y892520D01*
G37*
G36*
G01X675510D02*
X673310D01*
Y883420D01*
X675510D01*
Y892520D01*
G37*
G36*
G01X703856Y890820D02*
X701656D01*
Y883420D01*
X703856D01*
Y890820D01*
G37*
G36*
G01X700707Y892520D02*
X698507D01*
Y883420D01*
X700707D01*
Y892520D01*
G37*
G36*
G01X707006D02*
X704806D01*
Y883420D01*
X707006D01*
Y892520D01*
G37*
G36*
G01X722754D02*
X720554D01*
Y883420D01*
X722754D01*
Y892520D01*
G37*
G36*
G01X725904D02*
X723704D01*
Y883420D01*
X725904D01*
Y892520D01*
G37*
G36*
G01X729053D02*
X726853D01*
Y883420D01*
X729053D01*
Y892520D01*
G37*
G36*
G01X732203D02*
X730003D01*
Y883420D01*
X732203D01*
Y892520D01*
G37*
G36*
G01X735352D02*
X733152D01*
Y883420D01*
X735352D01*
Y892520D01*
G37*
G36*
G01X738502D02*
X736302D01*
Y883420D01*
X738502D01*
Y892520D01*
G37*
G36*
G01X741652D02*
X739452D01*
Y883420D01*
X741652D01*
Y892520D01*
G37*
G36*
G01X744801D02*
X742601D01*
Y883420D01*
X744801D01*
Y892520D01*
G37*
G36*
G01X747951D02*
X745751D01*
Y883420D01*
X747951D01*
Y892520D01*
G37*
G36*
G01X751100D02*
X748900D01*
Y883420D01*
X751100D01*
Y892520D01*
G37*
G36*
G01X754250D02*
X752050D01*
Y883420D01*
X754250D01*
Y892520D01*
G37*
G36*
G01X757400D02*
X755200D01*
Y883420D01*
X757400D01*
Y892520D01*
G37*
G36*
G01X760549D02*
X758349D01*
Y883420D01*
X760549D01*
Y892520D01*
G37*
G36*
G01X763699D02*
X761499D01*
Y883420D01*
X763699D01*
Y892520D01*
G37*
G36*
G01X766849D02*
X764649D01*
Y883420D01*
X766849D01*
Y892520D01*
G37*
G36*
G01X769998D02*
X767798D01*
Y883420D01*
X769998D01*
Y892520D01*
G37*
G36*
G01X773148D02*
X770948D01*
Y883420D01*
X773148D01*
Y892520D01*
G37*
G36*
G01X776297D02*
X774097D01*
Y883420D01*
X776297D01*
Y892520D01*
G37*
G36*
G01X779447D02*
X777247D01*
Y883420D01*
X779447D01*
Y892520D01*
G37*
G36*
G01X782597D02*
X780397D01*
Y883420D01*
X782597D01*
Y892520D01*
G37*
G36*
G01X785746D02*
X783546D01*
Y883420D01*
X785746D01*
Y892520D01*
G37*
G36*
G01X788896D02*
X786696D01*
Y883420D01*
X788896D01*
Y892520D01*
G37*
G36*
G01X792045D02*
X789845D01*
Y883420D01*
X792045D01*
Y892520D01*
G37*
G36*
G01X795195D02*
X792995D01*
Y883420D01*
X795195D01*
Y892520D01*
G37*
G36*
G01X798345D02*
X796145D01*
Y883420D01*
X798345D01*
Y892520D01*
G37*
G36*
G01X801494D02*
X799294D01*
Y883420D01*
X801494D01*
Y892520D01*
G37*
G36*
G01X804644D02*
X802444D01*
Y883420D01*
X804644D01*
Y892520D01*
G37*
G36*
G01X807793D02*
X805593D01*
Y883420D01*
X807793D01*
Y892520D01*
G37*
G36*
G01X810943D02*
X808743D01*
Y883420D01*
X810943D01*
Y892520D01*
G37*
G36*
G01X814093D02*
X811893D01*
Y883420D01*
X814093D01*
Y892520D01*
G37*
G36*
G01X817242D02*
X815042D01*
Y883420D01*
X817242D01*
Y892520D01*
G37*
G36*
G01X820392D02*
X818192D01*
Y883420D01*
X820392D01*
Y892520D01*
G37*
G36*
G01X823541D02*
X821341D01*
Y883420D01*
X823541D01*
Y892520D01*
G37*
G36*
G01X826691D02*
X824491D01*
Y883420D01*
X826691D01*
Y892520D01*
G37*
G36*
G01X829841D02*
X827641D01*
Y883420D01*
X829841D01*
Y892520D01*
G37*
G36*
G01X832990D02*
X830790D01*
Y883420D01*
X832990D01*
Y892520D01*
G37*
G36*
G01X836140D02*
X833940D01*
Y883420D01*
X836140D01*
Y892520D01*
G37*
G36*
G01X839289D02*
X837089D01*
Y883420D01*
X839289D01*
Y892520D01*
G37*
G36*
G01X842439D02*
X840239D01*
Y883420D01*
X842439D01*
Y892520D01*
G37*
G36*
G01X845589D02*
X843389D01*
Y883420D01*
X845589D01*
Y892520D01*
G37*
G36*
G01X848738D02*
X846538D01*
Y883420D01*
X848738D01*
Y892520D01*
G37*
G36*
G01X851888D02*
X849688D01*
Y883420D01*
X851888D01*
Y892520D01*
G37*
G36*
G01X855037D02*
X852837D01*
Y883420D01*
X855037D01*
Y892520D01*
G37*
G36*
G01X858187D02*
X855987D01*
Y883420D01*
X858187D01*
Y892520D01*
G37*
G36*
G01X1029841Y890820D02*
X1027641D01*
Y883420D01*
X1029841D01*
Y890820D01*
G37*
G36*
G01X1032990Y892520D02*
X1030790D01*
Y883420D01*
X1032990D01*
Y892520D01*
G37*
G36*
G01X1036140D02*
X1033940D01*
Y883420D01*
X1036140D01*
Y892520D01*
G37*
G36*
G01X1039289D02*
X1037089D01*
Y883420D01*
X1039289D01*
Y892520D01*
G37*
G36*
G01X1042439D02*
X1040239D01*
Y883420D01*
X1042439D01*
Y892520D01*
G37*
G36*
G01X1045589D02*
X1043389D01*
Y883420D01*
X1045589D01*
Y892520D01*
G37*
G36*
G01X1048738D02*
X1046538D01*
Y883420D01*
X1048738D01*
Y892520D01*
G37*
G36*
G01X1051888D02*
X1049688D01*
Y883420D01*
X1051888D01*
Y892520D01*
G37*
G36*
G01X1055037D02*
X1052837D01*
Y883420D01*
X1055037D01*
Y892520D01*
G37*
G36*
G01X1058187D02*
X1055987D01*
Y883420D01*
X1058187D01*
Y892520D01*
G37*
G36*
G01X1061337D02*
X1059137D01*
Y883420D01*
X1061337D01*
Y892520D01*
G37*
G36*
G01X1064486D02*
X1062286D01*
Y883420D01*
X1064486D01*
Y892520D01*
G37*
G36*
G01X1067636D02*
X1065436D01*
Y883420D01*
X1067636D01*
Y892520D01*
G37*
G36*
G01X1070786D02*
X1068586D01*
Y883420D01*
X1070786D01*
Y892520D01*
G37*
G36*
G01X1073935D02*
X1071735D01*
Y883420D01*
X1073935D01*
Y892520D01*
G37*
G36*
G01X1077085D02*
X1074885D01*
Y883420D01*
X1077085D01*
Y892520D01*
G37*
G36*
G01X1105431D02*
X1103231D01*
Y883420D01*
X1105431D01*
Y892520D01*
G37*
G36*
G01X1080234D02*
X1078034D01*
Y883420D01*
X1080234D01*
Y892520D01*
G37*
G36*
G01X1083384D02*
X1081184D01*
Y883420D01*
X1083384D01*
Y892520D01*
G37*
G36*
G01X1086534D02*
X1084334D01*
Y883420D01*
X1086534D01*
Y892520D01*
G37*
G36*
G01X1089683D02*
X1087483D01*
Y883420D01*
X1089683D01*
Y892520D01*
G37*
G36*
G01X1092833D02*
X1090633D01*
Y883420D01*
X1092833D01*
Y892520D01*
G37*
G36*
G01X1095982D02*
X1093782D01*
Y883420D01*
X1095982D01*
Y892520D01*
G37*
G36*
G01X1099132D02*
X1096932D01*
Y883420D01*
X1099132D01*
Y892520D01*
G37*
G36*
G01X1102282D02*
X1100082D01*
Y883420D01*
X1102282D01*
Y892520D01*
G37*
G36*
G01X1108581D02*
X1106381D01*
Y883420D01*
X1108581D01*
Y892520D01*
G37*
G36*
G01X1111730D02*
X1109530D01*
Y883420D01*
X1111730D01*
Y892520D01*
G37*
G36*
G01X1114880D02*
X1112680D01*
Y883420D01*
X1114880D01*
Y892520D01*
G37*
G36*
G01X1118030D02*
X1115830D01*
Y883420D01*
X1118030D01*
Y892520D01*
G37*
G36*
G01X1121179D02*
X1118979D01*
Y883420D01*
X1121179D01*
Y892520D01*
G37*
G36*
G01X1124329D02*
X1122129D01*
Y883420D01*
X1124329D01*
Y892520D01*
G37*
G36*
G01X1127478D02*
X1125278D01*
Y883420D01*
X1127478D01*
Y892520D01*
G37*
G36*
G01X1130628D02*
X1128428D01*
Y883420D01*
X1130628D01*
Y892520D01*
G37*
G36*
G01X1133778D02*
X1131578D01*
Y883420D01*
X1133778D01*
Y892520D01*
G37*
G36*
G01X1136927D02*
X1134727D01*
Y883420D01*
X1136927D01*
Y892520D01*
G37*
G36*
G01X1140077D02*
X1137877D01*
Y883420D01*
X1140077D01*
Y892520D01*
G37*
G36*
G01X1143226D02*
X1141026D01*
Y883420D01*
X1143226D01*
Y892520D01*
G37*
G36*
G01X1146376D02*
X1144176D01*
Y883420D01*
X1146376D01*
Y892520D01*
G37*
G36*
G01X1149526D02*
X1147326D01*
Y883420D01*
X1149526D01*
Y892520D01*
G37*
G36*
G01X1152675D02*
X1150475D01*
Y883420D01*
X1152675D01*
Y892520D01*
G37*
G36*
G01X1155825D02*
X1153625D01*
Y883420D01*
X1155825D01*
Y892520D01*
G37*
G36*
G01X1158974D02*
X1156774D01*
Y883420D01*
X1158974D01*
Y892520D01*
G37*
G36*
G01X1162124D02*
X1159924D01*
Y883420D01*
X1162124D01*
Y892520D01*
G37*
G36*
G01X1165274D02*
X1163074D01*
Y883420D01*
X1165274D01*
Y892520D01*
G37*
G36*
G01X1174723D02*
X1172523D01*
Y883420D01*
X1174723D01*
Y892520D01*
G37*
G36*
G01X1177872D02*
X1175672D01*
Y883420D01*
X1177872D01*
Y892520D01*
G37*
G36*
G01X1168423D02*
X1166223D01*
Y883420D01*
X1168423D01*
Y892520D01*
G37*
G36*
G01X1171573D02*
X1169373D01*
Y883420D01*
X1171573D01*
Y892520D01*
G37*
G36*
G01X1181022D02*
X1178822D01*
Y883420D01*
X1181022D01*
Y892520D01*
G37*
G36*
G01X1184171D02*
X1181971D01*
Y883420D01*
X1184171D01*
Y892520D01*
G37*
G36*
G01X1187321D02*
X1185121D01*
Y883420D01*
X1187321D01*
Y892520D01*
G37*
G36*
G01X1190471D02*
X1188271D01*
Y883420D01*
X1190471D01*
Y892520D01*
G37*
G36*
G01X1193620D02*
X1191420D01*
Y883420D01*
X1193620D01*
Y892520D01*
G37*
G36*
G01X1199919Y890820D02*
X1197719D01*
Y883420D01*
X1199919D01*
Y890820D01*
G37*
G36*
G01X1196770Y892520D02*
X1194570D01*
Y883420D01*
X1196770D01*
Y892520D01*
G37*
G36*
G01X1203069D02*
X1200869D01*
Y883420D01*
X1203069D01*
Y892520D01*
G37*
G36*
G01X1218817D02*
X1216617D01*
Y883420D01*
X1218817D01*
Y892520D01*
G37*
G36*
G01X1221967D02*
X1219767D01*
Y883420D01*
X1221967D01*
Y892520D01*
G37*
G36*
G01X1225116D02*
X1222916D01*
Y883420D01*
X1225116D01*
Y892520D01*
G37*
G36*
G01X1228266D02*
X1226066D01*
Y883420D01*
X1228266D01*
Y892520D01*
G37*
G36*
G01X1231415D02*
X1229215D01*
Y883420D01*
X1231415D01*
Y892520D01*
G37*
G36*
G01X1234565D02*
X1232365D01*
Y883420D01*
X1234565D01*
Y892520D01*
G37*
G36*
G01X1237715D02*
X1235515D01*
Y883420D01*
X1237715D01*
Y892520D01*
G37*
G36*
G01X1240864D02*
X1238664D01*
Y883420D01*
X1240864D01*
Y892520D01*
G37*
G36*
G01X1244014D02*
X1241814D01*
Y883420D01*
X1244014D01*
Y892520D01*
G37*
G36*
G01X1247163D02*
X1244963D01*
Y883420D01*
X1247163D01*
Y892520D01*
G37*
G36*
G01X1250313D02*
X1248113D01*
Y883420D01*
X1250313D01*
Y892520D01*
G37*
G36*
G01X1253463D02*
X1251263D01*
Y883420D01*
X1253463D01*
Y892520D01*
G37*
G36*
G01X1256612D02*
X1254412D01*
Y883420D01*
X1256612D01*
Y892520D01*
G37*
G36*
G01X1259762D02*
X1257562D01*
Y883420D01*
X1259762D01*
Y892520D01*
G37*
G36*
G01X1262912D02*
X1260712D01*
Y883420D01*
X1262912D01*
Y892520D01*
G37*
G36*
G01X1266061D02*
X1263861D01*
Y883420D01*
X1266061D01*
Y892520D01*
G37*
G36*
G01X1269211D02*
X1267011D01*
Y883420D01*
X1269211D01*
Y892520D01*
G37*
G36*
G01X1272360D02*
X1270160D01*
Y883420D01*
X1272360D01*
Y892520D01*
G37*
G36*
G01X1275510D02*
X1273310D01*
Y883420D01*
X1275510D01*
Y892520D01*
G37*
G36*
G01X1278660D02*
X1276460D01*
Y883420D01*
X1278660D01*
Y892520D01*
G37*
G36*
G01X1281809D02*
X1279609D01*
Y883420D01*
X1281809D01*
Y892520D01*
G37*
G36*
G01X1284959D02*
X1282759D01*
Y883420D01*
X1284959D01*
Y892520D01*
G37*
G36*
G01X1288108D02*
X1285908D01*
Y883420D01*
X1288108D01*
Y892520D01*
G37*
G36*
G01X1291258D02*
X1289058D01*
Y883420D01*
X1291258D01*
Y892520D01*
G37*
G36*
G01X1294408D02*
X1292208D01*
Y883420D01*
X1294408D01*
Y892520D01*
G37*
G36*
G01X1297557D02*
X1295357D01*
Y883420D01*
X1297557D01*
Y892520D01*
G37*
G36*
G01X1300707D02*
X1298507D01*
Y883420D01*
X1300707D01*
Y892520D01*
G37*
G36*
G01X1303856D02*
X1301656D01*
Y883420D01*
X1303856D01*
Y892520D01*
G37*
G36*
G01X1307006D02*
X1304806D01*
Y883420D01*
X1307006D01*
Y892520D01*
G37*
G36*
G01X1310156D02*
X1307956D01*
Y883420D01*
X1310156D01*
Y892520D01*
G37*
G36*
G01X1313305D02*
X1311105D01*
Y883420D01*
X1313305D01*
Y892520D01*
G37*
G36*
G01X1316455D02*
X1314255D01*
Y883420D01*
X1316455D01*
Y892520D01*
G37*
G36*
G01X1319604D02*
X1317404D01*
Y883420D01*
X1319604D01*
Y892520D01*
G37*
G36*
G01X1322754D02*
X1320554D01*
Y883420D01*
X1322754D01*
Y892520D01*
G37*
G36*
G01X1325904D02*
X1323704D01*
Y883420D01*
X1325904D01*
Y892520D01*
G37*
G36*
G01X1329053D02*
X1326853D01*
Y883420D01*
X1329053D01*
Y892520D01*
G37*
G36*
G01X1332203D02*
X1330003D01*
Y883420D01*
X1332203D01*
Y892520D01*
G37*
G36*
G01X1335352D02*
X1333152D01*
Y883420D01*
X1335352D01*
Y892520D01*
G37*
G36*
G01X1338502D02*
X1336302D01*
Y883420D01*
X1338502D01*
Y892520D01*
G37*
G36*
G01X1341652D02*
X1339452D01*
Y883420D01*
X1341652D01*
Y892520D01*
G37*
G36*
G01X1344801D02*
X1342601D01*
Y883420D01*
X1344801D01*
Y892520D01*
G37*
G36*
G01X1347951D02*
X1345751D01*
Y883420D01*
X1347951D01*
Y892520D01*
G37*
G36*
G01X1351100D02*
X1348900D01*
Y883420D01*
X1351100D01*
Y892520D01*
G37*
G36*
G01X1354250D02*
X1352050D01*
Y883420D01*
X1354250D01*
Y892520D01*
G37*
G54D10*
G01X127746Y-260199D02*
X95746D01*
G01X127746Y-276199D02*
Y-356199D01*
G01D02*
X1310146D01*
G01X127746Y-311699D02*
X1310146D01*
G01X123746Y-260199D02*
G02I-12000J0D01*
G01X118596D02*
G02I-6850J0D01*
G01X111746Y-276199D02*
Y-244199D01*
G01X127746Y-276199D02*
X1310146D01*
G01X522646D02*
Y-356199D01*
G01X660146Y-276199D02*
Y-356199D01*
G01X775146Y-276199D02*
Y-356199D01*
G01X942646Y-276199D02*
Y-356199D01*
G01X1112646Y-276199D02*
Y-356199D01*
G01X1310146Y-276199D02*
Y-356199D01*
G01X1342146Y-260199D02*
X1310146D01*
G01X1338146D02*
G02I-12000J0D01*
G01X1332996D02*
G02I-6850J0D01*
G01X1326146Y-276199D02*
Y-244199D01*
G54D11*
G01X145579Y-328699D02*
Y-346199D01*
X154313D01*
G01X167446Y-334533D02*
Y-346199D01*
G01Y-329866D02*
X167009Y-329574D01*
Y-328991D01*
X167446Y-328699D01*
X167883Y-328991D01*
Y-329574D01*
X167446Y-329866D01*
G01X181889Y-350574D02*
X183418Y-351741D01*
X185164Y-352032D01*
X186692Y-351741D01*
X188003Y-350283D01*
X188876Y-348241D01*
Y-334533D01*
G01Y-336866D02*
X188003Y-335699D01*
X186692Y-334824D01*
X185164Y-334533D01*
X183418Y-335116D01*
X182326Y-336282D01*
X181452Y-338324D01*
X181016Y-340366D01*
X181234Y-342116D01*
X182108Y-344158D01*
X183418Y-345616D01*
X185164Y-346199D01*
X186474Y-345907D01*
X188003Y-344741D01*
X188876Y-343575D01*
G01X198734Y-346199D02*
Y-328699D01*
G01Y-337157D02*
X199826Y-335699D01*
X200918Y-334824D01*
X202664Y-334533D01*
X203974Y-334824D01*
X205503Y-335991D01*
X206158Y-337741D01*
Y-346199D01*
G01X219946Y-328699D02*
Y-346199D01*
G01X216889Y-334533D02*
X223003D01*
G01X233734Y-346199D02*
Y-334533D01*
G01Y-337449D02*
X234608Y-335991D01*
X235918Y-334824D01*
X237664Y-334533D01*
X239192Y-334824D01*
X240503Y-335991D01*
X241158Y-338032D01*
Y-346199D01*
G01X254946Y-334533D02*
Y-346199D01*
G01Y-329866D02*
X254509Y-329574D01*
Y-328991D01*
X254946Y-328699D01*
X255383Y-328991D01*
Y-329574D01*
X254946Y-329866D01*
G01X268734Y-346199D02*
Y-334533D01*
G01Y-337449D02*
X269608Y-335991D01*
X270918Y-334824D01*
X272664Y-334533D01*
X274192Y-334824D01*
X275503Y-335991D01*
X276158Y-338032D01*
Y-346199D01*
G01X286889Y-350574D02*
X288418Y-351741D01*
X290164Y-352032D01*
X291692Y-351741D01*
X293003Y-350283D01*
X293876Y-348241D01*
Y-334533D01*
G01Y-336866D02*
X293003Y-335699D01*
X291692Y-334824D01*
X290164Y-334533D01*
X288418Y-335116D01*
X287326Y-336282D01*
X286452Y-338324D01*
X286016Y-340366D01*
X286234Y-342116D01*
X287108Y-344158D01*
X288418Y-345616D01*
X290164Y-346199D01*
X291474Y-345907D01*
X293003Y-344741D01*
X293876Y-343575D01*
G01X320579Y-346199D02*
Y-328699D01*
X325819D01*
X327566Y-329574D01*
X328876Y-331616D01*
X329313Y-333949D01*
X328876Y-336282D01*
X327784Y-338032D01*
X325819Y-338908D01*
X320579D01*
G01X346813Y-346199D02*
X338079D01*
Y-328699D01*
X346813D01*
G01X343319Y-337157D02*
X338079D01*
G01X361692Y-336866D02*
X362566Y-335991D01*
X363221Y-334533D01*
X363658Y-332490D01*
X363221Y-330741D01*
X362348Y-329574D01*
X360819Y-328699D01*
X354924D01*
Y-346199D01*
X362129D01*
X363658Y-345033D01*
X364531Y-343282D01*
X364968Y-341241D01*
X364531Y-339199D01*
X363221Y-337449D01*
X361692Y-336866D01*
X354924D01*
G01X390579Y-346199D02*
Y-328699D01*
X395819D01*
X397566Y-329574D01*
X398876Y-331616D01*
X399313Y-333949D01*
X398876Y-336282D01*
X397784Y-338032D01*
X395819Y-338908D01*
X390579D01*
G01X406769Y-346199D02*
Y-328699D01*
X412446Y-343282D01*
X418123Y-328699D01*
Y-346199D01*
G01X434749Y-330158D02*
X433439Y-329282D01*
X431911Y-328699D01*
X430164D01*
X428199Y-329574D01*
X426671Y-331032D01*
X425579Y-332783D01*
X424706Y-335699D01*
X424487Y-338324D01*
X424924Y-340949D01*
X425579Y-342699D01*
X426889Y-344449D01*
X428418Y-345616D01*
X429946Y-346199D01*
X431474D01*
X433003Y-345616D01*
X434313Y-344741D01*
X435405Y-343575D01*
G01X460579Y-346199D02*
Y-328699D01*
X465819D01*
X467566Y-329574D01*
X468876Y-331616D01*
X469313Y-333949D01*
X468876Y-336282D01*
X467784Y-338032D01*
X465819Y-338908D01*
X460579D01*
G01X476987Y-328699D02*
X482446Y-346199D01*
X487905Y-328699D01*
G01X499946D02*
Y-346199D01*
G01X494924Y-328699D02*
X504968D01*
G01X284269Y-301199D02*
Y-283699D01*
X289946Y-298282D01*
X295623Y-283699D01*
Y-301199D01*
G01X307446D02*
X306136Y-300907D01*
X304826Y-299741D01*
X303952Y-297699D01*
X303516Y-295366D01*
X303952Y-293032D01*
X304826Y-290991D01*
X306136Y-289824D01*
X307446Y-289533D01*
X308756Y-289824D01*
X310066Y-290991D01*
X310939Y-293032D01*
X311158Y-295366D01*
X310939Y-297699D01*
X310066Y-299741D01*
X308756Y-300907D01*
X307446Y-301199D01*
G01X328876Y-283699D02*
Y-301199D01*
G01Y-298575D02*
X328003Y-300033D01*
X326692Y-300907D01*
X325164Y-301199D01*
X323418Y-300616D01*
X322108Y-299158D01*
X321234Y-297408D01*
X321016Y-295366D01*
X321234Y-293324D01*
X322108Y-291574D01*
X323418Y-290116D01*
X325164Y-289533D01*
X326692Y-289824D01*
X327784Y-290408D01*
X328876Y-291574D01*
G01X339171Y-293324D02*
X346158D01*
X345503Y-291282D01*
X344411Y-290116D01*
X342883Y-289533D01*
X341354Y-289824D01*
X340044Y-290699D01*
X339171Y-292741D01*
X338734Y-294491D01*
Y-296241D01*
X339171Y-297991D01*
X340263Y-299741D01*
X341573Y-300907D01*
X343101Y-301199D01*
X344629Y-300616D01*
X346158Y-298866D01*
G01X359946Y-301199D02*
Y-283699D01*
G01X556346Y-346199D02*
Y-328699D01*
X553726Y-332199D01*
G01Y-346199D02*
X558966D01*
G01X569043Y-343575D02*
X570352Y-345033D01*
X571881Y-345907D01*
X573846Y-346199D01*
X575811Y-345616D01*
X577339Y-344449D01*
X578431Y-342408D01*
X578649Y-340074D01*
X578213Y-337741D01*
X577121Y-336282D01*
X575592Y-335116D01*
X574064Y-334824D01*
X572536Y-335116D01*
X570571Y-336282D01*
X571226Y-328699D01*
X577121D01*
G01X591346Y-346199D02*
Y-328699D01*
X588726Y-332199D01*
G01Y-346199D02*
X593966D01*
G01X608846Y-328699D02*
X607099Y-329282D01*
X605789Y-330741D01*
X604916Y-332490D01*
X604261Y-334824D01*
X604043Y-337449D01*
X604261Y-340074D01*
X604916Y-342408D01*
X605789Y-344158D01*
X607099Y-345616D01*
X608846Y-346199D01*
X610592Y-345616D01*
X611903Y-344158D01*
X612776Y-342408D01*
X613431Y-340074D01*
X613649Y-337449D01*
X613431Y-334824D01*
X612776Y-332490D01*
X611903Y-330741D01*
X610592Y-329282D01*
X608846Y-328699D01*
G01X621543Y-343575D02*
X622852Y-345033D01*
X624381Y-345907D01*
X626346Y-346199D01*
X628311Y-345616D01*
X629839Y-344449D01*
X630931Y-342408D01*
X631149Y-340074D01*
X630713Y-337741D01*
X629621Y-336282D01*
X628092Y-335116D01*
X626564Y-334824D01*
X625036Y-335116D01*
X623071Y-336282D01*
X623726Y-328699D01*
X629621D01*
G01X543229Y-301199D02*
Y-283699D01*
X548469D01*
X550216Y-284574D01*
X551526Y-286616D01*
X551963Y-288949D01*
X551526Y-291282D01*
X550434Y-293032D01*
X548469Y-293908D01*
X543229D01*
G01X569899Y-285158D02*
X568589Y-284282D01*
X567061Y-283699D01*
X565314D01*
X563349Y-284574D01*
X561821Y-286032D01*
X560729Y-287783D01*
X559856Y-290699D01*
X559637Y-293324D01*
X560074Y-295949D01*
X560729Y-297699D01*
X562039Y-299449D01*
X563568Y-300616D01*
X565096Y-301199D01*
X566624D01*
X568153Y-300616D01*
X569463Y-299741D01*
X570555Y-298575D01*
G01X584342Y-291866D02*
X585216Y-290991D01*
X585871Y-289533D01*
X586308Y-287490D01*
X585871Y-285741D01*
X584998Y-284574D01*
X583469Y-283699D01*
X577574D01*
Y-301199D01*
X584779D01*
X586308Y-300033D01*
X587181Y-298282D01*
X587618Y-296241D01*
X587181Y-294199D01*
X585871Y-292449D01*
X584342Y-291866D01*
X577574D01*
G01X593546Y-307032D02*
X606646D01*
G01X612574Y-301199D02*
Y-283699D01*
X622618Y-301199D01*
Y-283699D01*
G01X635096Y-301199D02*
X633349Y-300907D01*
X631821Y-299741D01*
X630511Y-297991D01*
X629637Y-295949D01*
X629201Y-293616D01*
Y-291282D01*
X629637Y-288949D01*
X630511Y-286907D01*
X631821Y-285158D01*
X633349Y-283991D01*
X635096Y-283699D01*
X636842Y-283991D01*
X638371Y-285158D01*
X639681Y-286907D01*
X640555Y-288949D01*
X640991Y-291282D01*
Y-293616D01*
X640555Y-295949D01*
X639681Y-297991D01*
X638371Y-299741D01*
X636842Y-300907D01*
X635096Y-301199D01*
G01X685937Y-283699D02*
X691396Y-301199D01*
X696855Y-283699D01*
G01X713263Y-301199D02*
X704529D01*
Y-283699D01*
X713263D01*
G01X709769Y-292157D02*
X704529D01*
G01X722029Y-301199D02*
Y-283699D01*
X727488D01*
X729234Y-284574D01*
X730326Y-285741D01*
X730763Y-288074D01*
X730326Y-290408D01*
X729016Y-291866D01*
X727488Y-292741D01*
X722029D01*
G01X727488D02*
X730763Y-301199D01*
G01X743896Y-301782D02*
X743459Y-301491D01*
Y-300907D01*
X743896Y-300616D01*
X744333Y-300907D01*
Y-301491D01*
X743896Y-301782D01*
G01X717646Y-346199D02*
Y-328699D01*
X715026Y-332199D01*
G01Y-346199D02*
X720266D01*
G01X816406Y-337449D02*
X820773D01*
Y-342699D01*
X819463Y-344449D01*
X817934Y-345616D01*
X815751Y-346199D01*
X813568Y-345616D01*
X812039Y-344449D01*
X810729Y-342699D01*
X809856Y-340657D01*
X809419Y-338324D01*
Y-336282D01*
X809856Y-334533D01*
X810729Y-332490D01*
X812039Y-330741D01*
X813349Y-329574D01*
X815096Y-328699D01*
X816624D01*
X818371Y-329282D01*
X819681Y-330449D01*
G01X832596Y-346199D02*
X830849Y-345907D01*
X829321Y-344741D01*
X828011Y-342991D01*
X827137Y-340949D01*
X826701Y-338616D01*
Y-336282D01*
X827137Y-333949D01*
X828011Y-331907D01*
X829321Y-330158D01*
X830849Y-328991D01*
X832596Y-328699D01*
X834342Y-328991D01*
X835871Y-330158D01*
X837181Y-331907D01*
X838055Y-333949D01*
X838491Y-336282D01*
Y-338616D01*
X838055Y-340949D01*
X837181Y-342991D01*
X835871Y-344741D01*
X834342Y-345907D01*
X832596Y-346199D01*
G01X845729Y-328699D02*
Y-346199D01*
X854463D01*
G01X862793D02*
Y-328699D01*
X867159D01*
X868906Y-329574D01*
X870216Y-330741D01*
X871308Y-332490D01*
X872181Y-334533D01*
X872399Y-337449D01*
X872181Y-340366D01*
X871308Y-342408D01*
X870216Y-344158D01*
X868906Y-345324D01*
X867159Y-346199D01*
X862793D01*
G01X878546Y-352032D02*
X891646D01*
G01X902596Y-328699D02*
Y-346199D01*
G01X897574Y-328699D02*
X907618D01*
G01X819479Y-283699D02*
Y-301199D01*
X828213D01*
G01X845276D02*
Y-289533D01*
G01Y-291574D02*
X844403Y-290408D01*
X843092Y-289824D01*
X841564Y-289533D01*
X840036Y-290116D01*
X838726Y-291282D01*
X837852Y-293032D01*
X837416Y-295366D01*
X837852Y-297699D01*
X838726Y-299449D01*
X840036Y-300616D01*
X841564Y-301199D01*
X843092Y-300907D01*
X844403Y-300033D01*
X845276Y-298866D01*
G01X854261Y-306449D02*
X855571Y-307032D01*
X857318Y-306449D01*
X858409Y-305283D01*
X859283Y-303824D01*
X860592Y-299158D01*
X863431Y-289533D01*
G01X856444D02*
X860592Y-299158D01*
G01X873071Y-293324D02*
X880058D01*
X879403Y-291282D01*
X878311Y-290116D01*
X876783Y-289533D01*
X875254Y-289824D01*
X873944Y-290699D01*
X873071Y-292741D01*
X872634Y-294491D01*
Y-296241D01*
X873071Y-297991D01*
X874163Y-299741D01*
X875473Y-300907D01*
X877001Y-301199D01*
X878529Y-300616D01*
X880058Y-298866D01*
G01X890789Y-301199D02*
Y-289533D01*
G01Y-291866D02*
X891881Y-290699D01*
X892973Y-289824D01*
X894501Y-289533D01*
X895592Y-289824D01*
X896903Y-290699D01*
G01X959846Y-328699D02*
X962902Y-346199D01*
X966396Y-328699D01*
X969889Y-346199D01*
X972946Y-328699D01*
G01X979529Y-346199D02*
Y-328699D01*
X984769D01*
X986516Y-329574D01*
X987826Y-331616D01*
X988263Y-333949D01*
X987826Y-336282D01*
X986734Y-338032D01*
X984769Y-338908D01*
X979529D01*
G01X996811Y-346199D02*
Y-328699D01*
G01X1005981D02*
Y-346199D01*
G01Y-337449D02*
X996811D01*
G01X1016058Y-340366D02*
X1021734D01*
G01X1031593Y-346199D02*
Y-328699D01*
G01X1039889D02*
X1031593Y-339491D01*
G01X1041199Y-346199D02*
X1035304Y-334533D01*
G01X1058263Y-346199D02*
X1049529D01*
Y-328699D01*
X1058263D01*
G01X1054769Y-337157D02*
X1049529D01*
G01X1066374Y-346199D02*
Y-328699D01*
X1076418Y-346199D01*
Y-328699D01*
G01X1083874Y-346199D02*
Y-328699D01*
X1093918Y-346199D01*
Y-328699D01*
G01X961593Y-301199D02*
Y-283699D01*
X965959D01*
X967706Y-284574D01*
X969016Y-285741D01*
X970108Y-287490D01*
X970981Y-289533D01*
X971199Y-292449D01*
X970981Y-295366D01*
X970108Y-297408D01*
X969016Y-299158D01*
X967706Y-300324D01*
X965959Y-301199D01*
X961593D01*
G01X980621Y-293324D02*
X987608D01*
X986953Y-291282D01*
X985861Y-290116D01*
X984333Y-289533D01*
X982804Y-289824D01*
X981494Y-290699D01*
X980621Y-292741D01*
X980184Y-294491D01*
Y-296241D01*
X980621Y-297991D01*
X981713Y-299741D01*
X983023Y-300907D01*
X984551Y-301199D01*
X986079Y-300616D01*
X987608Y-298866D01*
G01X998121Y-299158D02*
X999213Y-300324D01*
X1000741Y-301199D01*
X1002051D01*
X1003361Y-300616D01*
X1004234Y-299741D01*
X1004671Y-298575D01*
X1004453Y-296824D01*
X1003579Y-295949D01*
X999649Y-294199D01*
X998776Y-292157D01*
X999213Y-290699D01*
X1000086Y-289824D01*
X1001396Y-289533D01*
X1002706Y-289824D01*
X1004016Y-290699D01*
G01X1018896Y-289533D02*
Y-301199D01*
G01Y-284866D02*
X1018459Y-284574D01*
Y-283991D01*
X1018896Y-283699D01*
X1019333Y-283991D01*
Y-284574D01*
X1018896Y-284866D01*
G01X1033339Y-305574D02*
X1034868Y-306741D01*
X1036614Y-307032D01*
X1038142Y-306741D01*
X1039453Y-305283D01*
X1040326Y-303241D01*
Y-289533D01*
G01Y-291866D02*
X1039453Y-290699D01*
X1038142Y-289824D01*
X1036614Y-289533D01*
X1034868Y-290116D01*
X1033776Y-291282D01*
X1032902Y-293324D01*
X1032466Y-295366D01*
X1032684Y-297116D01*
X1033558Y-299158D01*
X1034868Y-300616D01*
X1036614Y-301199D01*
X1037924Y-300907D01*
X1039453Y-299741D01*
X1040326Y-298575D01*
G01X1050184Y-301199D02*
Y-289533D01*
G01Y-292449D02*
X1051058Y-290991D01*
X1052368Y-289824D01*
X1054114Y-289533D01*
X1055642Y-289824D01*
X1056953Y-290991D01*
X1057608Y-293032D01*
Y-301199D01*
G01X1068121Y-293324D02*
X1075108D01*
X1074453Y-291282D01*
X1073361Y-290116D01*
X1071833Y-289533D01*
X1070304Y-289824D01*
X1068994Y-290699D01*
X1068121Y-292741D01*
X1067684Y-294491D01*
Y-296241D01*
X1068121Y-297991D01*
X1069213Y-299741D01*
X1070523Y-300907D01*
X1072051Y-301199D01*
X1073579Y-300616D01*
X1075108Y-298866D01*
G01X1085839Y-301199D02*
Y-289533D01*
G01Y-291866D02*
X1086931Y-290699D01*
X1088023Y-289824D01*
X1089551Y-289533D01*
X1090642Y-289824D01*
X1091953Y-290699D01*
G01X1132596Y-346199D02*
Y-328699D01*
X1129976Y-332199D01*
G01Y-346199D02*
X1135216D01*
G01X1150096D02*
Y-328699D01*
X1147476Y-332199D01*
G01Y-346199D02*
X1152716D01*
G01X1163666Y-346782D02*
X1171526Y-328699D01*
G01X1185096Y-346199D02*
Y-328699D01*
X1182476Y-332199D01*
G01Y-346199D02*
X1187716D01*
G01X1198448Y-338908D02*
X1199976Y-336866D01*
X1201286Y-335699D01*
X1203033Y-335116D01*
X1204561Y-335699D01*
X1205653Y-336866D01*
X1206526Y-338616D01*
X1206744Y-340657D01*
X1206526Y-342408D01*
X1205653Y-344158D01*
X1204342Y-345616D01*
X1202814Y-346199D01*
X1201068Y-345616D01*
X1199539Y-343866D01*
X1198666Y-341241D01*
X1198448Y-338324D01*
X1198884Y-334533D01*
X1199539Y-332490D01*
X1200631Y-330449D01*
X1202159Y-328991D01*
X1203688Y-328699D01*
X1205216Y-329282D01*
X1206308Y-330741D01*
G01X1216166Y-346782D02*
X1224026Y-328699D01*
G01X1233448Y-331616D02*
X1234758Y-329866D01*
X1236286Y-328991D01*
X1238033Y-328699D01*
X1240216Y-329282D01*
X1241744Y-330741D01*
X1242181Y-332490D01*
X1241963Y-334241D01*
X1241089Y-335699D01*
X1236723Y-338616D01*
X1234758Y-340657D01*
X1233448Y-343575D01*
X1233011Y-346199D01*
X1242181D01*
G01X1255096Y-328699D02*
X1253349Y-329282D01*
X1252039Y-330741D01*
X1251166Y-332490D01*
X1250511Y-334824D01*
X1250293Y-337449D01*
X1250511Y-340074D01*
X1251166Y-342408D01*
X1252039Y-344158D01*
X1253349Y-345616D01*
X1255096Y-346199D01*
X1256842Y-345616D01*
X1258153Y-344158D01*
X1259026Y-342408D01*
X1259681Y-340074D01*
X1259899Y-337449D01*
X1259681Y-334824D01*
X1259026Y-332490D01*
X1258153Y-330741D01*
X1256842Y-329282D01*
X1255096Y-328699D01*
G01X1272596Y-346199D02*
Y-328699D01*
X1269976Y-332199D01*
G01Y-346199D02*
X1275216D01*
G01X1285948Y-338908D02*
X1287476Y-336866D01*
X1288786Y-335699D01*
X1290533Y-335116D01*
X1292061Y-335699D01*
X1293153Y-336866D01*
X1294026Y-338616D01*
X1294244Y-340657D01*
X1294026Y-342408D01*
X1293153Y-344158D01*
X1291842Y-345616D01*
X1290314Y-346199D01*
X1288568Y-345616D01*
X1287039Y-343866D01*
X1286166Y-341241D01*
X1285948Y-338324D01*
X1286384Y-334533D01*
X1287039Y-332490D01*
X1288131Y-330449D01*
X1289659Y-328991D01*
X1291188Y-328699D01*
X1292716Y-329282D01*
X1293808Y-330741D01*
G01X1180293Y-301199D02*
Y-283699D01*
X1184659D01*
X1186406Y-284574D01*
X1187716Y-285741D01*
X1188808Y-287490D01*
X1189681Y-289533D01*
X1189899Y-292449D01*
X1189681Y-295366D01*
X1188808Y-297408D01*
X1187716Y-299158D01*
X1186406Y-300324D01*
X1184659Y-301199D01*
X1180293D01*
G01X1206526D02*
Y-289533D01*
G01Y-291574D02*
X1205653Y-290408D01*
X1204342Y-289824D01*
X1202814Y-289533D01*
X1201286Y-290116D01*
X1199976Y-291282D01*
X1199102Y-293032D01*
X1198666Y-295366D01*
X1199102Y-297699D01*
X1199976Y-299449D01*
X1201286Y-300616D01*
X1202814Y-301199D01*
X1204342Y-300907D01*
X1205653Y-300033D01*
X1206526Y-298866D01*
G01X1220096Y-283699D02*
Y-301199D01*
G01X1217039Y-289533D02*
X1223153D01*
G01X1234321Y-293324D02*
X1241308D01*
X1240653Y-291282D01*
X1239561Y-290116D01*
X1238033Y-289533D01*
X1236504Y-289824D01*
X1235194Y-290699D01*
X1234321Y-292741D01*
X1233884Y-294491D01*
Y-296241D01*
X1234321Y-297991D01*
X1235413Y-299741D01*
X1236723Y-300907D01*
X1238251Y-301199D01*
X1239779Y-300616D01*
X1241308Y-298866D01*
G01X1425733Y-51181D02*
X-29385D01*
G01X-33322Y-47244D02*
G03X-29385Y-51181I3937J0D01*
G01X-33322Y-47244D02*
Y893701D01*
G01X-7874Y102402D02*
Y212205D01*
G01Y102402D02*
G03X0Y94528I7874J0D01*
G01Y212205D02*
G03X-7874I-3937J0D01*
G01Y237402D02*
G03X0I3937J-1D01*
G01X-7874D02*
Y406693D01*
G01X0D02*
G03X-7874I-3937J0D01*
G01Y431890D02*
G03X0I3937J0D01*
G01X-7874D02*
Y601181D01*
G01X0D02*
G03X-7874I-3937J0D01*
G01Y626378D02*
Y795669D01*
G01Y626378D02*
G03X0I3937J0D01*
G01Y795669D02*
G03X-7874I-3937J0D01*
G01Y820866D02*
G03X0I3937J0D01*
G01X-7874Y844488D02*
Y820866D01*
G01X-3937Y848425D02*
G03X-7874Y844488I0J-3937D01*
G01X93307Y848425D02*
X-3937D01*
G01X-29385Y897638D02*
G03X-33322Y893701I0J-3937D01*
G01X-29385Y897638D02*
X93307D01*
G01X98425Y94528D02*
X0D01*
G01X1400000Y36220D02*
G03X1398031Y38189I-1969J0D01*
G01X1396654D01*
G02X1394685Y40157I0J1969D01*
G01Y71654D01*
G02X1396654Y73622I1969J-1D01*
G01X1398031D01*
G03X1400000Y75591I0J1969D01*
G01Y836614D01*
G03X1396063Y840551I-3937J0D01*
G01X1368504D01*
G02X1363386Y845669I0J5118D01*
G01Y871654D01*
G03X1361417Y873622I-1969J-1D01*
G01X1358268D01*
G02X1356299Y875591I0J1969D01*
G01Y892521D01*
X1352363Y897638D01*
X1218110D01*
X1214173Y892520D01*
Y875984D01*
G02X1205512I-4331J0D01*
G01Y892520D01*
X1201575Y897638D01*
X1029528D01*
X1025591Y892520D01*
Y875591D01*
G02X1023622Y873622I-1969J0D01*
G01X1020472D01*
G03X1018504Y871654I0J-1968D01*
G01Y845669D01*
G02X1013386Y840551I-5118J0D01*
G01X1008433D01*
G03X988748Y820866I0J-19685D01*
G01Y650669D01*
G02X983748Y645669I-5000J0D01*
G01X926819D01*
G02X921819Y650669I0J5000D01*
G01Y820866D01*
G03X902134Y840551I-19685J0D01*
G01X872441D01*
G02X867323Y845669I0J5118D01*
G01Y871654D01*
G03X865354Y873622I-1969J-1D01*
G01X862205D01*
G02X860236Y875591I0J1969D01*
G01Y892521D01*
X856300Y897638D01*
X722048D01*
X718110Y892519D01*
Y875984D01*
G02X709449I-4331J0D01*
G01Y892520D01*
X705512Y897638D01*
X533465D01*
X529528Y892520D01*
Y875591D01*
G02X527559Y873622I-1969J0D01*
G01X524409D01*
G03X522441Y871654I0J-1968D01*
G01Y845669D01*
G02X517323Y840551I-5118J0D01*
G01X455118D01*
G02X450000Y845669I0J5118D01*
G01Y871654D01*
G03X448031Y873622I-1968J0D01*
G01X444882D01*
G02X442913Y875591I0J1969D01*
G01Y892521D01*
X438977Y897638D01*
X304725D01*
X300787Y892519D01*
Y875984D01*
G02X292126I-4331J0D01*
G01Y892521D01*
X288190Y897638D01*
X116142D01*
X112205Y892520D01*
Y875591D01*
G02X110236Y873622I-1969J0D01*
G01X107087D01*
G03X105118Y871654I0J-1969D01*
G01Y845669D01*
G02X100000Y840551I-5118J0D01*
G01X3937D01*
G03X0Y836614I0J-3937D01*
G01Y110276D01*
G03X7874Y102402I7874J0D01*
G01X196654D01*
G02X204528Y94528I0J-7874D01*
G01Y7874D01*
G03X212402Y0I7874J0D01*
G01X471014D01*
G02X478888Y-7874I0J-7874D01*
G01Y-11811D01*
G03X486762Y-19685I7874J0D01*
G01X1302165D01*
G03X1306102Y-15748I0J3937D01*
G01Y-3937D01*
G02X1310039Y0I3937J0D01*
G01X1396063D01*
G03X1400000Y3937I0J3937D01*
G01Y36220D01*
G01X93307Y848425D02*
G03X97244Y852362I0J3937D01*
G01Y893701D02*
Y852362D01*
G01Y893701D02*
G03X93307Y897638I-3937J0D01*
G01X192717Y94528D02*
X123622D01*
G01Y102402D02*
G03Y94528I0J-3937D01*
G01X98425D02*
G03Y102402I0J3937D01*
G01X196654Y0D02*
G03X204528Y-7874I7874J0D01*
G01X196654Y0D02*
Y29961D01*
G01X204528D02*
G03X196654I-3937J0D01*
G01Y55157D02*
Y90591D01*
G01Y55157D02*
G03X204528I3937J0D01*
G01X196654Y90591D02*
G03X192717Y94528I-3937J0D01*
G01X232077Y-7874D02*
G03Y0I0J3937D01*
G01Y-7874D02*
X204528D01*
G01X434439D02*
X257274D01*
G01Y0D02*
G03Y-7874I0J-3937D01*
G01X365945Y38188D02*
G03X367914Y40156I0J1969D01*
G01X354134D02*
G03X356103Y38188I1969J1D01*
G01D02*
X365945D01*
G01X354134Y71653D02*
Y40156D01*
G01X367914Y71653D02*
G03X365945Y73621I-1969J-1D01*
G01X356103D02*
G03X354134Y71653I0J-1969D01*
G01X365945Y73621D02*
X356103D01*
G01X367914Y40156D02*
Y71653D01*
G01X434439Y-7874D02*
G03Y0I0J3937D01*
G01X471014Y-15748D02*
G03X463140Y-7874I-7874J0D01*
G01D02*
X459636D01*
G01Y0D02*
G03Y-7874I0J-3937D01*
G01X707234Y-27559D02*
X478888D01*
G01X471014Y-19685D02*
G03X478888Y-27559I7874J0D01*
G01X471014Y-19685D02*
Y-15748D01*
G01X870226Y-27559D02*
X732431D01*
G01Y-19685D02*
G03Y-27559I0J-3937D01*
G01X707234D02*
G03Y-19685I0J3937D01*
G01X870226Y-27559D02*
G03Y-19685I1J3937D01*
G01X1072589Y-27559D02*
X895423D01*
G01Y-19685D02*
G03Y-27559I0J-3937D01*
G01X1072589D02*
G03Y-19685I0J3937D01*
G01X1097785D02*
G03Y-27559I1J-3937D01*
G01X1336086Y-8662D02*
X1318701D01*
G03X1314764Y-12599I0J-3937D01*
G01Y-23622D01*
G02X1310827Y-27559I-3937J0D01*
G01X1097785D01*
G01X1336086Y-8662D02*
G03Y-1I0J4330D01*
G01X1361283D02*
G03Y-8662I0J-4330D01*
G01X1407874Y13026D02*
Y-4725D01*
G02X1403937Y-8662I-3937J0D01*
G01X1361283D01*
G01X1403937Y848425D02*
X1375197D01*
G01X1371260Y852362D02*
G03X1375197Y848425I3937J0D01*
G01X1371260Y852362D02*
Y893701D01*
G01X1375197Y897638D02*
G03X1371260Y893701I0J-3937D01*
G01X1375197Y897638D02*
X1425733D01*
G01X1407874Y30709D02*
Y219685D01*
G01X1400000Y30709D02*
G03X1407874I3937J0D01*
G01Y13026D02*
G03X1400000I-3937J-1D01*
G01X1407874Y219685D02*
G03X1400000I-3937J0D01*
G01Y244882D02*
G03X1407874I3937J0D01*
G01Y414173D02*
Y244882D01*
G01Y608661D02*
Y439370D01*
G01X1400000D02*
G03X1407874I3937J0D01*
G01Y414173D02*
G03X1400000I-3937J0D01*
G01X1407874Y608661D02*
G03X1400000I-3937J0D01*
G01Y626378D02*
G03X1407874I3937J0D01*
G01Y795669D02*
Y626378D01*
G01Y795669D02*
G03X1400000I-3937J0D01*
G01Y820866D02*
G03X1407874I3937J0D01*
G01Y844488D02*
Y820866D01*
G01Y844488D02*
G03X1403937Y848425I-3937J0D01*
G01X1429670Y893701D02*
Y-47244D01*
G01X1425733Y-51181D02*
G03X1429670Y-47244I0J3937D01*
G01Y893701D02*
G03X1425733Y897638I-3937J0D01*
M02*
